FILE_TYPE = CONNECTIVITY;
{Allegro Design Entry HDL 17.4-2019 S026 (4007227) 1/17/2022}
"PAGE_NUMBER" = 462;
0"NC";
1"GND\g";
2"GND\g";
3"GND\g";
4"P1V8_CPU1_RT_1D\g";
5"GND\g";
6"GND\g";
7"P1V8_CPU1_RT_1D\g";
8"GND\g";
9"GND\g";
10"GND\g";
11"P1V8_CPU1_RT_1D\g";
12"GND\g";
13"GND\g";
14"GND\g";
15"P1V8_CPU1_RT_1D\g";
16"SMB_RT_CPU1_P3_ROM_MUX_1D_SCL";
17"SMB_RT_CPU1_P3_ROM_MUX_1D_R_SCL";
18"TEST0_RT_CPU1_P3";
19"SMB_RT_CPU1_P3_ROM_MUX_1D_R_SDA";
20"SMB_RT_CPU1_P3_ROM_MUX_1D_SDA";
21"RT_CPU1_P3_SCAN_MODE";
22"P1V8_CPU1_RT_1D\g";
23"P1V8_CPU1_RT_1D\g";
24"GND\g";
25"GND\g";
26"P1V8_CPU1_RT_1D\g";
27"JTAG_TDI_RT_CPU1_P3";
28"JTAG_TDO_RT_CPU1_P3";
29"JTAG_TMS_RT_CPU1_P3";
30"JTAG_TCK_RT_CPU1_P3";
31"RST_RT_CPU1_P3_RESET_R_N";
32"RST_RT_CPU1_P3_PERST_R_N";
33"JTAG_TDI_RT_CPU1_P3";
34"JTAG_TMS_RT_CPU1_P3";
35"JTAG_TDO_RT_CPU1_P3";
36"JTAG_TCK_RT_CPU1_P3";
37"JTAG_TRST_RT_CPU1_P3_N";
38"JTAG_TEST_MODE_RT_CPU1_P3";
39"MODE_RT_CPU1_P3";
40"RXDET_BYP_RT_CPU1_P3";
41"RT_CPU1_P3_SCAN_MODE";
42"RST_RT_CPU1_P3_RESET_N";
43"RST_RT_CPU1_P3_PERST_N";
44"CLKREQ_RT_CPU1_P3_N";
45"GPIO3_RT_CPU1_P3";
46"GPIO2_RT_CPU1_P3";
47"RXDET_BYP_RT_CPU1_P3";
48"SMB_RT_CPU1_P3_R2_SDA";
49"SMB_RT_CPU1_P3_R2_SCL";
50"RST_RT_CPU1_P3_RESET_R_N";
51"RST_RT_CPU1_P3_PERST_R_N";
52"RT_CPU1_P3_ADDR2";
53"RT_CPU1_P3_ADDR3";
54"MODE_RT_CPU1_P3";
55"JTAG_TEST_MODE_RT_CPU1_P3";
56"TEST2_RT_CPU1_P3";
57"TEST1_RT_CPU1_P3";
58"TEST0_RT_CPU1_P3";
59"GPIO2_RT_CPU1_P3";
60"SMB_RT_CPU1_P3_R_SCL";
61"GPIO3_RT_CPU1_P3";
62"RT_CPU1_P3_ADDR1";
63"RT_CPU1_P3_ADDR3";
64"RT_CPU1_P3_ADDR2";
65"RT_CPU1_P3_ADDR1";
66"TEST2_RT_CPU1_P3";
67"CLK_100M_RETIMER_CPU1_P3_DP";
68"CLK_100M_RETIMER_CPU1_P3_R_DP";
69"CLK_100M_RETIMER_CPU1_P3_DN";
70"CLK_100M_RETIMER_CPU1_P3_R_DN";
71"SMB_RT_CPU1_P3_R_SDA";
72"TEST1_RT_CPU1_P3";
%"Q_RES"
"1","(-2750,3250)","0","pure_quanta","I103";
;
LOCATION"R1429"
$SEC"1"
CDS_SEC"1"
MATERIAL"CHIP"
VALUE"1K"
PACK_TYPE"0201LF"
CDS_LIB"pure_quanta"
WATTAGE"1/20W"
TOLERANCE"1%"
PART_NUMBER"CS21001FE07";
"B"
$PN"2"3;
"A"
$PN"1"37;
%"UNIVERSAL_GND"
"1","(-2000,2300)","1","pure_quanta_power","I107";
;
CDS_LIB"pure_quanta_power"
HDL_POWER"GND";
"A"1;
%"GND"
"1","(-1525,2800)","0","pure_quanta_power","I108";
;
BOM_COST"MEM"
SIZE"1B"
CDS_LIB"pure_quanta_power"
HDL_POWER"GND";
"A<SIZE-1..0>\NAC"2;
%"UNIVERSAL_GND"
"1","(-2000,3250)","1","pure_quanta_power","I110";
;
CDS_LIB"pure_quanta_power"
HDL_POWER"GND";
"A"3;
%"Q_RES"
"2","(-1525,3200)","0","pure_quanta","I114";
;
LOCATION"R1435"
$SEC"1"
CDS_SEC"1"
PACK_TYPE"0201LF"
WATTAGE"1/20W"
VALUE"10K"
TOLERANCE"1%"
MATERIAL"CHIP"
CDS_LIB"pure_quanta"
PART_NUMBER"CS31001FE17";
"A"
$PN"1"47;
"B"
$PN"2"2;
%"Q_RES"
"2","(-1525,3725)","0","pure_quanta","I115";
;
LOCATION"R1434"
$SEC"1"
CDS_SEC"1"
TOLERANCE"1%"
WATTAGE"1/20W"
PACK_TYPE"0201LF"
MATERIAL"EMPTY"
VALUE"1K"
CDS_LIB"pure_quanta"
PART_NUMBER"CS21001FE07";
"A"
$PN"1"4;
"B"
$PN"2"47;
%"P1V0"
"1","(-1525,4125)","0","pure_quanta_power","I117";
;
HDL_POWER"P1V8_CPU1_RT_1D"
CDS_LIB"pure_quanta_power";
"A"4;
%"Q_RES"
"2","(-9025,3450)","0","pure_quanta","I119";
;
LOCATION"R910"
$SEC"1"
CDS_SEC"1"
PACK_TYPE"0201LF"
TOLERANCE"1%"
VALUE"200"
WATTAGE"1/20W"
MATERIAL"CHIP"
CDS_LIB"pure_quanta"
PART_NUMBER"CS12001FE12";
"A"
$PN"1"21;
"B"
$PN"2"6;
%"Q_RES"
"2","(-1125,1350)","0","pure_quanta","I132";
;
LOCATION"R1511"
$SEC"1"
CDS_SEC"1"
MATERIAL"EMPTY"
PACK_TYPE"0201LF"
WATTAGE"1/20W"
TOLERANCE"5%"
VALUE"4.7K"
CDS_LIB"pure_quanta"
PART_NUMBER"CS24701JE04";
"A"
$PN"1"22;
"B"
$PN"2"29;
%"GND"
"1","(-575,425)","0","pure_quanta_power","I134";
;
SIZE"1B"
BOM_COST"MEM"
CDS_LIB"pure_quanta_power"
HDL_POWER"GND";
"A<SIZE-1..0>\NAC"5;
%"Q_RES"
"2","(-575,725)","0","pure_quanta","I136";
;
LOCATION"R1430"
$SEC"1"
CDS_SEC"1"
WATTAGE"1/20W"
VALUE"4.7K"
TOLERANCE"5%"
PACK_TYPE"0201LF"
MATERIAL"CHIP"
CDS_LIB"pure_quanta"
PART_NUMBER"CS24701JE04";
"A"
$PN"1"30;
"B"
$PN"2"5;
%"Q_RES"
"2","(-575,1375)","0","pure_quanta","I137";
;
LOCATION"R1513"
$SEC"1"
CDS_SEC"1"
TOLERANCE"5%"
WATTAGE"1/20W"
VALUE"4.7K"
PACK_TYPE"0201LF"
MATERIAL"EMPTY"
CDS_LIB"pure_quanta"
PART_NUMBER"CS24701JE04";
"A"
$PN"1"22;
"B"
$PN"2"30;
%"P1V0"
"1","(-575,1675)","0","pure_quanta_power","I138";
;
HDL_POWER"P1V8_CPU1_RT_1D"
CDS_LIB"pure_quanta_power";
"A"22;
%"Q_RES"
"2","(-1400,1350)","0","pure_quanta","I139";
;
LOCATION"R1510"
$SEC"1"
CDS_SEC"1"
VALUE"4.7K"
PACK_TYPE"0201LF"
MATERIAL"EMPTY"
TOLERANCE"5%"
WATTAGE"1/20W"
CDS_LIB"pure_quanta"
PART_NUMBER"CS24701JE04";
"A"
$PN"1"22;
"B"
$PN"2"27;
%"Q_RES"
"2","(-850,1350)","0","pure_quanta","I140";
;
LOCATION"R1512"
$SEC"1"
CDS_SEC"1"
TOLERANCE"1%"
WATTAGE"1/20W"
VALUE"1K"
PACK_TYPE"0201LF"
MATERIAL"EMPTY"
CDS_LIB"pure_quanta"
PART_NUMBER"CS21001FE07";
"A"
$PN"1"22;
"B"
$PN"2"28;
%"Q_RES"
"1","(-6375,1650)","0","pure_quanta","I146";
;
LOCATION"R695"
SEC"1"
TOLERANCE"1%"
VALUE"22"
WATTAGE"1/20W"
MATERIAL"CHIP"
PACK_TYPE"0201LF"
CDS_LIB"pure_quanta"
SEC_TYPE"0201LF"
PART_NUMBER"CS02201FE11";
"B"
$PN"2"17;
"A"
$PN"1"16;
%"UNIVERSAL_GND"
"1","(-9025,3175)","0","pure_quanta_power","I15";
;
CDS_LIB"pure_quanta_power"
HDL_POWER"GND";
"A"6;
%"Q_RES"
"2","(-9025,4125)","0","pure_quanta","I17";
;
LOCATION"R909"
$SEC"1"
CDS_SEC"1"
VALUE"4.7K"
TOLERANCE"5%"
WATTAGE"1/20W"
MATERIAL"EMPTY"
PACK_TYPE"0201LF"
CDS_LIB"pure_quanta"
PART_NUMBER"CS24701JE04";
"A"
$PN"1"7;
"B"
$PN"2"21;
%"P1V0"
"1","(-9025,4450)","0","pure_quanta_power","I18";
;
HDL_POWER"P1V8_CPU1_RT_1D"
CDS_LIB"pure_quanta_power";
"A"7;
%"Q_RES"
"2","(-9000,5050)","0","pure_quanta","I19";
;
LOCATION"R916"
$SEC"1"
CDS_SEC"1"
VALUE"10K"
TOLERANCE"1%"
WATTAGE"1/20W"
MATERIAL"CHIP"
PACK_TYPE"0201LF"
CDS_LIB"pure_quanta"
PART_NUMBER"CS31001FE17";
"A"
$PN"1"59;
"B"
$PN"2"24;
%"Q_RES"
"2","(-8700,5050)","0","pure_quanta","I20";
;
LOCATION"R917"
$SEC"1"
CDS_SEC"1"
WATTAGE"1/20W"
MATERIAL"CHIP"
VALUE"10K"
TOLERANCE"1%"
PACK_TYPE"0201LF"
CDS_LIB"pure_quanta"
PART_NUMBER"CS31001FE17";
"A"
$PN"1"61;
"B"
$PN"2"24;
%"Q_RES"
"2","(-8375,5050)","0","pure_quanta","I21";
;
LOCATION"R919"
$SEC"1"
CDS_SEC"1"
TOLERANCE"5%"
PACK_TYPE"0201LF"
MATERIAL"CHIP"
WATTAGE"1/20W"
VALUE"4.7K"
CDS_LIB"pure_quanta"
PART_NUMBER"CS24701JE04";
"A"
$PN"1"58;
"B"
$PN"2"24;
%"Q_RES"
"2","(-9000,6000)","0","pure_quanta","I22";
;
LOCATION"R915"
$SEC"1"
CDS_SEC"1"
TOLERANCE"5%"
PACK_TYPE"0201LF"
MATERIAL"EMPTY"
WATTAGE"1/20W"
VALUE"4.7K"
CDS_LIB"pure_quanta"
PART_NUMBER"CS24701JE04";
"A"
$PN"1"23;
"B"
$PN"2"59;
%"Q_RES"
"2","(-8375,6000)","0","pure_quanta","I23";
;
LOCATION"R918"
$SEC"1"
CDS_SEC"1"
TOLERANCE"5%"
PACK_TYPE"0201LF"
MATERIAL"EMPTY"
WATTAGE"1/20W"
VALUE"4.7K"
CDS_LIB"pure_quanta"
PART_NUMBER"CS24701JE04";
"A"
$PN"1"23;
"B"
$PN"2"58;
%"P1V0"
"1","(-9000,6400)","0","pure_quanta_power","I24";
;
HDL_POWER"P1V8_CPU1_RT_1D"
CDS_LIB"pure_quanta_power";
"A"23;
%"UNIVERSAL_GND"
"1","(-6350,400)","0","pure_quanta_power","I29";
;
CDS_LIB"pure_quanta_power"
HDL_POWER"GND";
"A"8;
%"Q_RES"
"2","(-6350,725)","2","pure_quanta","I30";
;
LOCATION"R641"
$SEC"1"
CDS_SEC"1"
WATTAGE"1/20W"
MATERIAL"EMPTY"
PACK_TYPE"0201LF"
TOLERANCE"1%"
VALUE"51.1"
CDS_LIB"pure_quanta"
PART_NUMBER"CS05111FE00";
"A"
$PN"1"69;
"B"
$PN"2"8;
%"Q_RES"
"1","(-6650,1050)","0","pure_quanta","I31";
;
LOCATION"R622"
SEC"1"
PACK_TYPE"0201LF"
MATERIAL"CHIP"
CDS_LIB"pure_quanta"
TOLERANCE"5%"
VALUE"0"
WATTAGE"1/20W"
SEC_TYPE"0201LF"
PART_NUMBER"CS00001JE10";
"B"
$PN"2"69;
"A"
$PN"1"70;
%"Q_RES"
"1","(-6650,1200)","0","pure_quanta","I32";
;
LOCATION"R621"
SEC"1"
MATERIAL"CHIP"
WATTAGE"1/20W"
PACK_TYPE"0201LF"
VALUE"0"
TOLERANCE"5%"
CDS_LIB"pure_quanta"
SEC_TYPE"0201LF"
PART_NUMBER"CS00001JE10";
"B"
$PN"2"67;
"A"
$PN"1"68;
%"Q_RES"
"1","(-6375,1550)","0","pure_quanta","I33";
;
LOCATION"R696"
$SEC"1"
CDS_SEC"1"
VALUE"49.9"
WATTAGE"1/20W"
TOLERANCE"1%"
PACK_TYPE"0201LF"
MATERIAL"CHIP"
CDS_LIB"pure_quanta"
PART_NUMBER"CS04991FE06";
"B"
$PN"2"19;
"A"
$PN"1"20;
%"Q_RES"
"1","(-6400,2800)","0","pure_quanta","I41";
;
LOCATION"R914"
$SEC"1"
CDS_SEC"1"
WATTAGE"1/20W"
VALUE"0"
TOLERANCE"5%"
MATERIAL"CHIP"
PACK_TYPE"0201LF"
CDS_LIB"pure_quanta"
PART_NUMBER"CS00001JE10";
"B"
$PN"2"48;
"A"
$PN"1"71;
%"Q_RES"
"1","(-6400,2900)","0","pure_quanta","I42";
;
LOCATION"R913"
$SEC"1"
CDS_SEC"1"
VALUE"0"
PACK_TYPE"0201LF"
MATERIAL"CHIP"
WATTAGE"1/20W"
TOLERANCE"5%"
CDS_LIB"pure_quanta"
PART_NUMBER"CS00001JE10";
"B"
$PN"2"49;
"A"
$PN"1"60;
%"UNIVERSAL_GND"
"1","(-6200,400)","0","pure_quanta_power","I45";
;
CDS_LIB"pure_quanta_power"
HDL_POWER"GND";
"A"9;
%"Q_RES"
"2","(-6200,725)","0","pure_quanta","I46";
;
LOCATION"R642"
$SEC"1"
CDS_SEC"1"
VALUE"51.1"
PACK_TYPE"0201LF"
MATERIAL"EMPTY"
WATTAGE"1/20W"
TOLERANCE"1%"
CDS_LIB"pure_quanta"
PART_NUMBER"CS05111FE00";
"A"
$PN"1"67;
"B"
$PN"2"9;
%"Q_RES"
"2","(-8075,5025)","0","pure_quanta","I50";
;
LOCATION"R921"
$SEC"1"
CDS_SEC"1"
VALUE"4.7K"
PACK_TYPE"0201LF"
TOLERANCE"5%"
WATTAGE"1/20W"
MATERIAL"CHIP"
CDS_LIB"pure_quanta"
PART_NUMBER"CS24701JE04";
"A"
$PN"1"57;
"B"
$PN"2"24;
%"Q_RES"
"2","(-7775,5025)","0","pure_quanta","I51";
;
LOCATION"R923"
$SEC"1"
CDS_SEC"1"
WATTAGE"1/20W"
MATERIAL"CHIP"
PACK_TYPE"0201LF"
VALUE"4.7K"
TOLERANCE"5%"
CDS_LIB"pure_quanta"
PART_NUMBER"CS24701JE04";
"A"
$PN"1"56;
"B"
$PN"2"24;
%"UNIVERSAL_GND"
"1","(-7475,4550)","0","pure_quanta_power","I52";
;
CDS_LIB"pure_quanta_power"
HDL_POWER"GND";
"A"24;
%"Q_RES"
"2","(-7475,5000)","0","pure_quanta","I53";
;
LOCATION"R924"
$SEC"1"
CDS_SEC"1"
WATTAGE"1/20W"
VALUE"4.7K"
PACK_TYPE"0201LF"
MATERIAL"CHIP"
TOLERANCE"5%"
CDS_LIB"pure_quanta"
PART_NUMBER"CS24701JE04";
"A"
$PN"1"55;
"B"
$PN"2"24;
%"Q_RES"
"2","(-8075,5950)","0","pure_quanta","I54";
;
LOCATION"R920"
$SEC"1"
CDS_SEC"1"
MATERIAL"EMPTY"
PACK_TYPE"0201LF"
WATTAGE"1/20W"
TOLERANCE"5%"
VALUE"4.7K"
CDS_LIB"pure_quanta"
PART_NUMBER"CS24701JE04";
"A"
$PN"1"23;
"B"
$PN"2"57;
%"Q_RES"
"2","(-7775,5975)","0","pure_quanta","I55";
;
LOCATION"R922"
$SEC"1"
CDS_SEC"1"
VALUE"4.7K"
WATTAGE"1/20W"
MATERIAL"EMPTY"
PACK_TYPE"0201LF"
TOLERANCE"5%"
CDS_LIB"pure_quanta"
PART_NUMBER"CS24701JE04";
"A"
$PN"1"23;
"B"
$PN"2"56;
%"Q_RES"
"2","(-7475,6000)","0","pure_quanta","I56";
;
LOCATION"R912"
$SEC"1"
CDS_SEC"1"
PACK_TYPE"0201LF"
WATTAGE"1/20W"
MATERIAL"EMPTY"
TOLERANCE"5%"
VALUE"4.7K"
CDS_LIB"pure_quanta"
PART_NUMBER"CS24701JE04";
"A"
$PN"1"23;
"B"
$PN"2"55;
%"UNIVERSAL_GND"
"1","(-5075,5200)","0","pure_quanta_power","I63";
;
CDS_LIB"pure_quanta_power"
HDL_POWER"GND";
"A"10;
%"Q_RES"
"2","(-5075,5550)","0","pure_quanta","I64";
;
LOCATION"R926"
$SEC"1"
CDS_SEC"1"
MATERIAL"EMPTY"
TOLERANCE"5%"
PACK_TYPE"0201LF"
WATTAGE"1/20W"
VALUE"4.7K"
CDS_LIB"pure_quanta"
PART_NUMBER"CS24701JE04";
"A"
$PN"1"54;
"B"
$PN"2"10;
%"Q_RES"
"2","(-5075,6075)","0","pure_quanta","I65";
;
LOCATION"R925"
$SEC"1"
CDS_SEC"1"
VALUE"4.7K"
TOLERANCE"5%"
WATTAGE"1/20W"
MATERIAL"CHIP"
PACK_TYPE"0201LF"
CDS_LIB"pure_quanta"
PART_NUMBER"CS24701JE04";
"A"
$PN"1"11;
"B"
$PN"2"54;
%"P1V0"
"1","(-5075,6400)","0","pure_quanta_power","I67";
;
HDL_POWER"P1V8_CPU1_RT_1D"
CDS_LIB"pure_quanta_power";
"A"11;
%"UNIVERSAL_GND"
"1","(-2675,1700)","1","pure_quanta_power","I68";
;
CDS_LIB"pure_quanta_power"
HDL_POWER"GND";
"A"12;
%"Q_RES"
"1","(-2625,2200)","0","pure_quanta","I69";
;
LOCATION"R895"
SEC"1"
PACK_TYPE"0201LF"
VALUE"0"
WATTAGE"1/20W"
TOLERANCE"5%"
MATERIAL"CHIP"
SEC_TYPE"0201LF"
CDS_LIB"pure_quanta"
PART_NUMBER"CS00001JE10";
"B"
$PN"2"32;
"A"
$PN"1"43;
%"Q_RES"
"1","(-2625,2100)","0","pure_quanta","I70";
;
LOCATION"R901"
$SEC"1"
CDS_SEC"1"
PACK_TYPE"0201LF"
VALUE"0"
CDS_LIB"pure_quanta"
MATERIAL"CHIP"
TOLERANCE"5%"
WATTAGE"1/20W"
PART_NUMBER"CS00001JE10";
"B"
$PN"2"31;
"A"
$PN"1"42;
%"UNIVERSAL_GND"
"1","(-3675,4900)","0","pure_quanta_power","I78";
;
CDS_LIB"pure_quanta_power"
HDL_POWER"GND";
"A"25;
%"Q_RES"
"2","(-3675,5325)","0","pure_quanta","I79";
;
LOCATION"R903"
$SEC"1"
CDS_SEC"1"
MATERIAL"EMPTY"
PACK_TYPE"0201LF"
WATTAGE"1/20W"
TOLERANCE"1%"
VALUE"1K"
CDS_LIB"pure_quanta"
PART_NUMBER"CS21001FE07";
"A"
$PN"1"53;
"B"
$PN"2"25;
%"Q_RES"
"2","(-3675,6100)","0","pure_quanta","I80";
;
LOCATION"R902"
$SEC"1"
CDS_SEC"1"
MATERIAL"CHIP"
PACK_TYPE"0201LF"
WATTAGE"1/20W"
TOLERANCE"1%"
VALUE"1K"
CDS_LIB"pure_quanta"
PART_NUMBER"CS21001FE07";
"A"
$PN"1"26;
"B"
$PN"2"53;
%"Q_RES"
"2","(-3375,5325)","0","pure_quanta","I81";
;
LOCATION"R906"
$SEC"1"
CDS_SEC"1"
VALUE"20K"
PACK_TYPE"0201LF"
WATTAGE"1/20W"
MATERIAL"CHIP"
TOLERANCE"1%"
CDS_LIB"pure_quanta"
PART_NUMBER"CS32001FE00";
"A"
$PN"1"52;
"B"
$PN"2"25;
%"Q_RES"
"2","(-3375,6100)","0","pure_quanta","I82";
;
LOCATION"R904"
$SEC"1"
CDS_SEC"1"
PACK_TYPE"0201LF"
MATERIAL"EMPTY"
WATTAGE"1/20W"
VALUE"1K"
TOLERANCE"1%"
CDS_LIB"pure_quanta"
PART_NUMBER"CS21001FE07";
"A"
$PN"1"26;
"B"
$PN"2"52;
%"Q_RES"
"2","(-3025,5325)","0","pure_quanta","I83";
;
LOCATION"R949"
$SEC"1"
CDS_SEC"1"
MATERIAL"CHIP"
WATTAGE"1/20W"
VALUE"1K"
PACK_TYPE"0201LF"
TOLERANCE"1%"
CDS_LIB"pure_quanta"
PART_NUMBER"CS21001FE07";
"A"
$PN"1"65;
"B"
$PN"2"25;
%"Q_RES"
"2","(-3025,6075)","0","pure_quanta","I84";
;
LOCATION"R927"
$SEC"1"
CDS_SEC"1"
WATTAGE"1/20W"
PACK_TYPE"0201LF"
VALUE"1K"
TOLERANCE"1%"
MATERIAL"EMPTY"
CDS_LIB"pure_quanta"
PART_NUMBER"CS21001FE07";
"A"
$PN"1"26;
"B"
$PN"2"65;
%"P1V0"
"1","(-3675,6525)","0","pure_quanta_power","I88";
;
HDL_POWER"P1V8_CPU1_RT_1D"
CDS_LIB"pure_quanta_power";
"A"26;
%"GND"
"1","(-1525,4850)","0","pure_quanta_power","I89";
;
CDS_LIB"pure_quanta_power"
SIZE"1B"
BOM_COST"MEM"
HDL_POWER"GND";
"A<SIZE-1..0>\NAC"13;
%"Q_RES"
"2","(-1525,5225)","2","pure_quanta","I90";
;
LOCATION"R908"
$SEC"1"
CDS_SEC"1"
PACK_TYPE"0201LF"
VALUE"10K"
WATTAGE"1/20W"
TOLERANCE"1%"
MATERIAL"CHIP"
CDS_LIB"pure_quanta"
PART_NUMBER"CS31001FE17";
"A"
$PN"1"50;
"B"
$PN"2"13;
%"GND"
"1","(-1350,4875)","0","pure_quanta_power","I91";
;
SIZE"1B"
BOM_COST"MEM"
CDS_LIB"pure_quanta_power"
HDL_POWER"GND";
"A<SIZE-1..0>\NAC"14;
%"Q_RES"
"2","(-1350,5225)","0","pure_quanta","I92";
;
LOCATION"R907"
$SEC"1"
CDS_SEC"1"
VALUE"10K"
TOLERANCE"1%"
PACK_TYPE"0201LF"
WATTAGE"1/20W"
MATERIAL"CHIP"
CDS_LIB"pure_quanta"
PART_NUMBER"CS31001FE17";
"A"
$PN"1"51;
"B"
$PN"2"14;
%"Q_RES"
"2","(-1525,6050)","2","pure_quanta","I93";
;
LOCATION"R911"
$SEC"1"
CDS_SEC"1"
PACK_TYPE"0201LF"
MATERIAL"EMPTY"
VALUE"4.7K"
WATTAGE"1/20W"
TOLERANCE"5%"
CDS_LIB"pure_quanta"
PART_NUMBER"CS24701JE04";
"A"
$PN"1"15;
"B"
$PN"2"50;
%"P1V0"
"1","(-1525,6300)","0","pure_quanta_power","I96";
;
HDL_POWER"P1V8_CPU1_RT_1D"
CDS_LIB"pure_quanta_power";
"A"15;
%"PT5161LRS"
"3","(-4425,2350)","0","pure_quanta","I97";
;
LOCATION"U6017"
$SEC"3"
CDS_SEC"3"
MATERIAL"IC"
VALUE"PT5161LRS"
PART_TYPE"SMLF"
NEEDS_NO_SIZE"TRUE"
CDS_LMAN_SYM_OUTLINE"-500,1450,450,-1400"
CDS_LIB"pure_quanta"
PART_NUMBER"AJ051610U03";
"EE_DAT"
$PN"FJ3"19;
"EE_CLK"
$PN"FF5"17;
"CLKREQ_N \B"
$PN"G35"44;
"TEST2"
$PN"FF30"66;
"TEST1"
$PN"FF27"72;
"TEST0"
$PN"FF24"18;
"T_SENSE"
$PN"E30"12;
"SMBDAT"
$PN"B28"48;
"SMBCLK"
$PN"B31"49;
"SMB_ADDR3"
$PN"B25"63;
"SMB_ADDR2"
$PN"B23"64;
"SMB_ADDR1"
$PN"F34"62;
"SCAN_MODE"
$PN"FF33"41;
"RXDET_BYP"
$PN"E11"40;
"RESET_N \B"
$PN"FF11"42;
"REFCLKP"
$PN"FJ16"67;
"REFCLKN"
$PN"FF18"69;
"REFCLK_OUTP"
$PN"B16"0;
"REFCLK_OUTN"
$PN"E18"0;
"PERST_N \B"
$PN"F2"43;
"MODE"
$PN"FJ9"39;
"JTAG_TRST_N \B"
$PN"E8"37;
"JTAG_TMS"
$PN"B12"34;
"JTAG_TEST_MODE"
$PN"FF8"38;
"JTAG_TDO"
$PN"B9"35;
"JTAG_TDI"
$PN"B6"33;
"JTAG_TCK"
$PN"B3"36;
"INT_N \B"
$PN"FJ31"0;
"GPIO3"
$PN"FJ28"45;
"GPIO2"
$PN"FJ25"46;
"GPIO1"
$PN"FJ23"0;
"GPIO0"
$PN"FJ6"0;
%"Q_RES"
"1","(-2725,2300)","0","pure_quanta","I98";
;
LOCATION"R1433"
$SEC"1"
CDS_SEC"1"
MATERIAL"CHIP"
VALUE"4.7K"
PACK_TYPE"0201LF"
WATTAGE"1/20W"
TOLERANCE"5%"
CDS_LIB"pure_quanta"
PART_NUMBER"CS24701JE04";
"B"
$PN"2"1;
"A"
$PN"1"44;
END.
